# S9S_MB_2U (Grand Teton) — schematic netlist excerpt (pin names and nets, part order shuffled) for the footprints in the layout excerpt that follows; sources: Cadence DE-HDL packaged netlist, KiCad conversion of 03242023_DA0F0TMBIJ0_F0T_Motherboard_J_brd_V01_OCP.brd

PR51  Q_RES  12.4K 0.1% CHIP  pkg 0402LF  page 300 : A = PVNN_MAIN_CPU1_FB ; B = GND
R3126  Q_RES  0 5% CHIP  pkg 0402LF  page 236 : A = SMB_S3M_CPU1_PIROM_3V3AUX_SDA_R ; B = SMB_S3M_CPU1_PIROM_3V3AUX_SDA
C891  Q_CAP_DIFFBUS  DIFF BUS_0.22UF 6.3V 20% X6S  pkg C0201  page 174 : \1\ = P5E_CPU0_PE3_TX_C_DP<5> ; \2\ = P5E_CPU0_PE3_TX_DP<5>

(kicad_pcb
	(version 20260206)
	(generator "pcbnew")
	(generator_version "10.0")
	(general
		(thickness 1.6)
		(legacy_teardrops no)
	)
	(paper "A4")
	(title_block
		(title "03242023_DA0F0TMBIJ0_F0T_Motherboard_J_brd_V01_OCP.brd")
		(comment 1 "Grand Teton / footprints 1883-1885 of 6105")
	)
	(layers
		(0 "F.Cu" signal "TOP")
		(4 "In1.Cu" signal "GND")
		(6 "In2.Cu" signal "IN1")
		(8 "In3.Cu" signal "GND1")
		(10 "In4.Cu" signal "IN2")
		(12 "In5.Cu" signal "GND2")
		(14 "In6.Cu" signal "IN3")
		(16 "In7.Cu" signal "GND3")
		(18 "In8.Cu" signal "VCC")
		(20 "In9.Cu" signal "VCC1")
		(22 "In10.Cu" signal "GND4")
		(24 "In11.Cu" signal "IN4")
		(26 "In12.Cu" signal "GND5")
		(28 "In13.Cu" signal "IN5")
		(30 "In14.Cu" signal "GND6")
		(32 "In15.Cu" signal "IN6")
		(34 "In16.Cu" signal "GND7")
		(2 "B.Cu" signal "BOTTOM")
		(9 "F.Adhes" user "F.Adhesive")
		(11 "B.Adhes" user "B.Adhesive")
		(13 "F.Paste" user "Package Geometry/Pastemask Top")
		(15 "B.Paste" user "Package Geometry/Pastemask Bottom")
		(5 "F.SilkS" user "Ref Des/Silkscreen Top")
		(7 "B.SilkS" user "Ref Des/Silkscreen Bottom")
		(1 "F.Mask" user "Board Geometry/Soldermask Top")
		(3 "B.Mask" user "Board Geometry/Soldermask Bottom")
		(17 "Dwgs.User" user "User.Drawings")
		(19 "Cmts.User" user "User.Comments")
		(21 "Eco1.User" user "User.Eco1")
		(23 "Eco2.User" user "User.Eco2")
		(25 "Edge.Cuts" user "Board Geometry/Outline")
		(27 "Margin" user)
		(31 "F.CrtYd" user "Package Geometry/Place Bound Top")
		(29 "B.CrtYd" user "Package Geometry/Place Bound Bottom")
		(35 "F.Fab" user "Ref Des/Assembly Top")
		(33 "B.Fab" user "Ref Des/Assembly Bottom")
	)
	(footprint ""
		(layer "F.Cu")
		(at 22.100032 -176.329086)
		(property "Reference" "PR51"
			(at 0 0 0)
			(layer "F.SilkS")
			(hide yes)
			(effects
				(font
					(size 1.27 1.27)
				)
			)
		)
		(property "Value" ""
			(at 0 0 0)
			(layer "F.Fab")
			(effects
				(font
					(size 1.27 1.27)
				)
			)
		)
		(duplicate_pad_numbers_are_jumpers no)
		(fp_line
			(start -0.7874 -0.4064)
			(end 0.7874 -0.4064)
			(stroke
				(width 0.1524)
				(type default)
			)
			(layer "F.SilkS")
		)
		(fp_line
			(start -0.7874 0.4064)
			(end -0.7874 -0.4064)
			(stroke
				(width 0.1524)
				(type default)
			)
			(layer "F.SilkS")
		)
		(fp_line
			(start 0.7874 -0.4064)
			(end 0.7874 0.4064)
			(stroke
				(width 0.1524)
				(type default)
			)
			(layer "F.SilkS")
		)
		(fp_line
			(start 0.7874 0.4064)
			(end -0.7874 0.4064)
			(stroke
				(width 0.1524)
				(type default)
			)
			(layer "F.SilkS")
		)
		(fp_line
			(start -0.67945 -0.305054)
			(end -0.12065 -0.305054)
			(stroke
				(width 0.1)
				(type default)
			)
			(layer "F.Fab")
		)
		(fp_line
			(start -0.67945 0.3048)
			(end -0.67945 -0.305054)
			(stroke
				(width 0.1)
				(type default)
			)
			(layer "F.Fab")
		)
		(fp_line
			(start -0.12065 -0.305054)
			(end -0.12065 -0.2794)
			(stroke
				(width 0.1)
				(type default)
			)
			(layer "F.Fab")
		)
		(fp_line
			(start -0.12065 -0.2794)
			(end 0.12065 -0.2794)
			(stroke
				(width 0.1)
				(type default)
			)
			(layer "F.Fab")
		)
		(fp_line
			(start -0.12065 0.2794)
			(end -0.12065 0.3048)
			(stroke
				(width 0.1)
				(type default)
			)
			(layer "F.Fab")
		)
		(fp_line
			(start -0.12065 0.3048)
			(end -0.67945 0.3048)
			(stroke
				(width 0.1)
				(type default)
			)
			(layer "F.Fab")
		)
		(fp_line
			(start 0.120396 0.2794)
			(end -0.12065 0.2794)
			(stroke
				(width 0.1)
				(type default)
			)
			(layer "F.Fab")
		)
		(fp_line
			(start 0.120396 0.3048)
			(end 0.120396 0.2794)
			(stroke
				(width 0.1)
				(type default)
			)
			(layer "F.Fab")
		)
		(fp_line
			(start 0.12065 -0.3048)
			(end 0.67945 -0.3048)
			(stroke
				(width 0.1)
				(type default)
			)
			(layer "F.Fab")
		)
		(fp_line
			(start 0.12065 -0.2794)
			(end 0.12065 -0.3048)
			(stroke
				(width 0.1)
				(type default)
			)
			(layer "F.Fab")
		)
		(fp_line
			(start 0.67945 -0.3048)
			(end 0.67945 0.3048)
			(stroke
				(width 0.1)
				(type default)
			)
			(layer "F.Fab")
		)
		(fp_line
			(start 0.67945 0.3048)
			(end 0.120396 0.3048)
			(stroke
				(width 0.1)
				(type default)
			)
			(layer "F.Fab")
		)
		(pad "1" smd circle
			(at -0.40005 0)
			(size 0 0)
			(layers "F.Cu" "F.Mask" "F.Paste")
			(net "PVNN_MAIN_CPU1_FB")
		)
		(pad "2" smd circle
			(at 0.40005 0)
			(size 0 0)
			(layers "F.Cu" "F.Mask" "F.Paste")
			(net "GND")
		)
	)
	(footprint ""
		(layer "F.Cu")
		(at 157.351984 -81.90738 90)
		(property "Reference" "R3126"
			(at 0 0 90)
			(layer "F.SilkS")
			(hide yes)
			(effects
				(font
					(size 1.27 1.27)
				)
			)
		)
		(property "Value" ""
			(at 0 0 90)
			(layer "F.Fab")
			(effects
				(font
					(size 1.27 1.27)
				)
			)
		)
		(duplicate_pad_numbers_are_jumpers no)
		(fp_line
			(start 0.7874 -0.4064)
			(end 0.7874 0.4064)
			(stroke
				(width 0.1524)
				(type default)
			)
			(layer "F.SilkS")
		)
		(fp_line
			(start -0.7874 -0.4064)
			(end 0.7874 -0.4064)
			(stroke
				(width 0.1524)
				(type default)
			)
			(layer "F.SilkS")
		)
		(fp_line
			(start 0.7874 0.4064)
			(end -0.7874 0.4064)
			(stroke
				(width 0.1524)
				(type default)
			)
			(layer "F.SilkS")
		)
		(fp_line
			(start -0.7874 0.4064)
			(end -0.7874 -0.4064)
			(stroke
				(width 0.1524)
				(type default)
			)
			(layer "F.SilkS")
		)
		(fp_line
			(start -0.12065 -0.305054)
			(end -0.12065 -0.2794)
			(stroke
				(width 0.1)
				(type default)
			)
			(layer "F.Fab")
		)
		(fp_line
			(start -0.67945 -0.305054)
			(end -0.12065 -0.305054)
			(stroke
				(width 0.1)
				(type default)
			)
			(layer "F.Fab")
		)
		(fp_line
			(start 0.67945 -0.3048)
			(end 0.67945 0.3048)
			(stroke
				(width 0.1)
				(type default)
			)
			(layer "F.Fab")
		)
		(fp_line
			(start 0.12065 -0.3048)
			(end 0.67945 -0.3048)
			(stroke
				(width 0.1)
				(type default)
			)
			(layer "F.Fab")
		)
		(fp_line
			(start 0.12065 -0.2794)
			(end 0.12065 -0.3048)
			(stroke
				(width 0.1)
				(type default)
			)
			(layer "F.Fab")
		)
		(fp_line
			(start -0.12065 -0.2794)
			(end 0.12065 -0.2794)
			(stroke
				(width 0.1)
				(type default)
			)
			(layer "F.Fab")
		)
		(fp_line
			(start 0.120396 0.2794)
			(end -0.12065 0.2794)
			(stroke
				(width 0.1)
				(type default)
			)
			(layer "F.Fab")
		)
		(fp_line
			(start -0.12065 0.2794)
			(end -0.12065 0.3048)
			(stroke
				(width 0.1)
				(type default)
			)
			(layer "F.Fab")
		)
		(fp_line
			(start 0.67945 0.3048)
			(end 0.120396 0.3048)
			(stroke
				(width 0.1)
				(type default)
			)
			(layer "F.Fab")
		)
		(fp_line
			(start 0.120396 0.3048)
			(end 0.120396 0.2794)
			(stroke
				(width 0.1)
				(type default)
			)
			(layer "F.Fab")
		)
		(fp_line
			(start -0.12065 0.3048)
			(end -0.67945 0.3048)
			(stroke
				(width 0.1)
				(type default)
			)
			(layer "F.Fab")
		)
		(fp_line
			(start -0.67945 0.3048)
			(end -0.67945 -0.305054)
			(stroke
				(width 0.1)
				(type default)
			)
			(layer "F.Fab")
		)
		(pad "1" smd circle
			(at -0.40005 0 90)
			(size 0 0)
			(layers "F.Cu" "F.Mask" "F.Paste")
			(net "SMB_S3M_CPU1_PIROM_3V3AUX_SDA_R")
		)
		(pad "2" smd circle
			(at 0.40005 0 90)
			(size 0 0)
			(layers "F.Cu" "F.Mask" "F.Paste")
			(net "SMB_S3M_CPU1_PIROM_3V3AUX_SDA")
		)
	)
	(footprint ""
		(layer "F.Cu")
		(at 404.29053 -408.517344 -90)
		(property "Reference" "C891"
			(at 0 0 270)
			(layer "F.SilkS")
			(hide yes)
			(effects
				(font
					(size 1.27 1.27)
				)
			)
		)
		(property "Value" ""
			(at 0 0 270)
			(layer "F.Fab")
			(effects
				(font
					(size 1.27 1.27)
				)
			)
		)
		(duplicate_pad_numbers_are_jumpers no)
		(fp_line
			(start -0.299974 0.150114)
			(end -0.299974 -0.150114)
			(stroke
				(width 0.1)
				(type default)
			)
			(layer "F.Fab")
		)
		(fp_line
			(start 0.299974 0.150114)
			(end -0.299974 0.150114)
			(stroke
				(width 0.1)
				(type default)
			)
			(layer "F.Fab")
		)
		(fp_line
			(start -0.299974 -0.150114)
			(end 0.299974 -0.150114)
			(stroke
				(width 0.1)
				(type default)
			)
			(layer "F.Fab")
		)
		(fp_line
			(start 0.299974 -0.150114)
			(end 0.299974 0.150114)
			(stroke
				(width 0.1)
				(type default)
			)
			(layer "F.Fab")
		)
		(pad "1" smd rect
			(at -0.2667 0 270)
			(size 0.3048 0.381)
			(layers "F.Cu" "F.Mask" "F.Paste")
			(net "P5E_CPU0_PE3_TX_C_DP<5>")
		)
		(pad "2" smd rect
			(at 0.2667 0 270)
			(size 0.3048 0.381)
			(layers "F.Cu" "F.Mask" "F.Paste")
			(net "P5E_CPU0_PE3_TX_DP<5>")
		)
	)
)
